# BASEBOARD_FAB2 (Tioga Pass) — schematic netlist excerpt (pin names and nets, part order shuffled) for the footprints in the layout excerpt that follows; sources: Cadence DE-HDL packaged netlist, KiCad conversion of Wiwynn_Tioga_Pass_MB.brd

EU1C3  IR354XX  IR35411 IC  pkg SM  page 209
  VOS  = PVCCIN_CPU1
  LGND  = GND
  VCC  = VR_PVCCIN_CPU1_PH5_VCIN
  VDRV  = P5V_STBY
  PGND(0)  = GND
  GL(0)  = TP_PVCCIN_CPU1_PH5_GL_0
  PGND(1)  = GND
  SW  = VR_PVCCIN_CPU1_PHASE5
  VIN(0)  = VR_FET_SW_P12V_STBY_PVCCIN_CPU1
  VIN(1)  = VR_FET_SW_P12V_STBY_PVCCIN_CPU1
  NC  = NC
  PHASE  = VR_PVCCIN_CPU1_PH5_PHASE
  BOOST  = VR_PVCCIN_CPU1_PH5_BOOT_R
  PWM  = VR_PVCCIN_CPU1_PWM5
  EN  = P5V_STBY
  TOUT_FLT  = A_TSENSE_PVCCIN_CPU1
  OCSET  = VR_PVCCIN_CPU1_PH5_OCSET
  IOUT  = ISENSE_PVCCIN_CPU1_PH5_IMON
  REFIN  = VR_PVCCIN_CPU1_AIREF5
  PGND(2)  = GND
  GL(1)  = TP_PVCCIN_CPU1_PH5_GL_1

(kicad_pcb
	(version 20260206)
	(generator "pcbnew")
	(generator_version "10.0")
	(general
		(thickness 1.6)
		(legacy_teardrops no)
	)
	(paper "A4")
	(title_block
		(title "Wiwynn_Tioga_Pass_MB.brd")
		(comment 1 "Tioga Pass / footprints 780-780 of 4770")
	)
	(layers
		(0 "F.Cu" signal "TOP")
		(4 "In1.Cu" signal "L2GND")
		(6 "In2.Cu" signal "L3")
		(8 "In3.Cu" signal "L4GND")
		(10 "In4.Cu" signal "L5")
		(12 "In5.Cu" signal "L6GND")
		(14 "In6.Cu" signal "L7VCC")
		(16 "In7.Cu" signal "L8VCC")
		(18 "In8.Cu" signal "L9GND")
		(20 "In9.Cu" signal "L10")
		(22 "In10.Cu" signal "L11GND")
		(24 "In11.Cu" signal "L12")
		(26 "In12.Cu" signal "L13GND")
		(2 "B.Cu" signal "BOTTOM")
		(9 "F.Adhes" user "F.Adhesive")
		(11 "B.Adhes" user "B.Adhesive")
		(13 "F.Paste" user "Package Geometry/Pastemask Top")
		(15 "B.Paste" user "Package Geometry/Pastemask Bottom")
		(5 "F.SilkS" user "Ref Des/Silkscreen Top")
		(7 "B.SilkS" user "Ref Des/Silkscreen Bottom")
		(1 "F.Mask" user "Board Geometry/Soldermask Top")
		(3 "B.Mask" user "Board Geometry/Soldermask Bottom")
		(17 "Dwgs.User" user "User.Drawings")
		(19 "Cmts.User" user "User.Comments")
		(21 "Eco1.User" user "User.Eco1")
		(23 "Eco2.User" user "User.Eco2")
		(25 "Edge.Cuts" user "Board Geometry/Outline")
		(27 "Margin" user)
		(31 "F.CrtYd" user "Package Geometry/Place Bound Top")
		(29 "B.CrtYd" user "Package Geometry/Place Bound Bottom")
		(35 "F.Fab" user "Ref Des/Assembly Top")
		(33 "B.Fab" user "Ref Des/Assembly Bottom")
	)
	(footprint ""
		(layer "F.Cu")
		(at 33.925002 -89.551764 90)
		(property "Reference" "EU1C3"
			(at 1.226566 -8.144002 0)
			(unlocked yes)
			(layer "F.SilkS")
			(effects
				(font
					(size 0.7874 0.5842)
					(thickness 0.1524)
				)
			)
		)
		(property "Value" ""
			(at 0 0 90)
			(layer "F.Fab")
			(effects
				(font
					(size 1.27 1.27)
				)
			)
		)
		(duplicate_pad_numbers_are_jumpers no)
		(fp_line
			(start 2.9718 -3.5052)
			(end 2.9718 3.429)
			(stroke
				(width 0.1524)
				(type default)
			)
			(layer "F.SilkS")
		)
		(fp_line
			(start -3.0099 -3.5052)
			(end 2.9718 -3.5052)
			(stroke
				(width 0.1524)
				(type default)
			)
			(layer "F.SilkS")
		)
		(fp_line
			(start 2.9718 3.429)
			(end -3.0099 3.429)
			(stroke
				(width 0.1524)
				(type default)
			)
			(layer "F.SilkS")
		)
		(fp_line
			(start -3.0099 3.429)
			(end -3.0099 -3.5052)
			(stroke
				(width 0.1524)
				(type default)
			)
			(layer "F.SilkS")
		)
		(fp_circle
			(center -3.057398 -2.678684)
			(end -3.057398 -2.551684)
			(stroke
				(width 0.254)
				(type default)
			)
			(fill no)
			(layer "F.SilkS")
		)
		(fp_poly
			(pts
				(xy -2.9972 -3.4925) (xy -2.9972 -2.6924) (xy -2.1971 -3.4925)
			)
			(stroke
				(width 0)
				(type default)
			)
			(fill yes)
			(layer "F.SilkS")
		)
		(fp_poly
			(pts
				(xy -2.549906 -3.050032) (xy -2.549906 3.050032) (xy 2.549906 3.050032) (xy 2.549906 -3.050032)
			)
			(stroke
				(width 0)
				(type default)
			)
			(fill no)
			(layer "F.CrtYd")
		)
		(fp_line
			(start 2.549906 -3.050032)
			(end 2.549906 3.050032)
			(stroke
				(width 0.1)
				(type default)
			)
			(layer "F.Fab")
		)
		(fp_line
			(start -2.549906 -3.050032)
			(end 2.549906 -3.050032)
			(stroke
				(width 0.1)
				(type default)
			)
			(layer "F.Fab")
		)
		(fp_line
			(start 2.549906 3.050032)
			(end -2.549906 3.050032)
			(stroke
				(width 0.1)
				(type default)
			)
			(layer "F.Fab")
		)
		(fp_line
			(start -2.549906 3.050032)
			(end -2.549906 -3.050032)
			(stroke
				(width 0.1)
				(type default)
			)
			(layer "F.Fab")
		)
		(fp_circle
			(center -3.057398 -2.678684)
			(end -3.057398 -2.551684)
			(stroke
				(width 0.254)
				(type default)
			)
			(fill no)
			(layer "F.Fab")
		)
		(pad "1" smd rect
			(at -2.39522 -2.279904 90)
			(size 0.7112 0.254)
			(layers "F.Cu" "F.Mask" "F.Paste")
			(net "PVCCIN_CPU1")
		)
		(pad "2" smd rect
			(at -2.39522 -1.83007 90)
			(size 0.7112 0.254)
			(layers "F.Cu" "F.Mask" "F.Paste")
			(net "GND")
		)
		(pad "3" smd rect
			(at -2.39522 -1.379982 90)
			(size 0.7112 0.254)
			(layers "F.Cu" "F.Mask" "F.Paste")
			(net "VR_PVCCIN_CPU1_PH5_VCIN")
		)
		(pad "4" smd rect
			(at -2.39522 -0.929894 90)
			(size 0.7112 0.254)
			(layers "F.Cu" "F.Mask" "F.Paste")
			(net "P5V_STBY")
		)
		(pad "5" smd rect
			(at -2.39522 -0.48006 90)
			(size 0.7112 0.254)
			(layers "F.Cu" "F.Mask" "F.Paste")
			(net "GND")
		)
		(pad "6" smd rect
			(at -2.39522 -0.029972 90)
			(size 0.7112 0.254)
			(layers "F.Cu" "F.Mask" "F.Paste")
			(net "TP_PVCCIN_CPU1_PH5_GL_0")
		)
		(pad "7" smd custom
			(at 0.016764 1.145032 90)
			(size 0.53975 0.53975)
			(layers "F.Cu" "F.Mask" "F.Paste")
			(net "GND")
			(options
				(clearance outline)
				(anchor circle)
			)
			(primitives
				(gr_poly
					(pts
						(xy -2.7051 1.0795) (xy -2.7051 -0.3683) (xy -0.9271 -0.3683) (xy -0.9271 -1.0795) (xy 2.7051 -1.0795)
						(xy 2.7051 1.0795)
					)
					(width 0)
					(fill yes)
				)
			)
		)
		(pad "10" smd rect
			(at -0.008382 2.874772 90)
			(size 4.3434 0.6096)
			(layers "F.Cu" "F.Mask" "F.Paste")
			(net "VR_PVCCIN_CPU1_PHASE5")
		)
		(pad "25" smd rect
			(at 1.548384 -1.283208 90)
			(size 2.3368 2.0066)
			(layers "F.Cu" "F.Mask" "F.Paste")
			(net "VR_FET_SW_P12V_STBY_PVCCIN_CPU1")
		)
		(pad "30" smd rect
			(at 2.050034 -2.895092 90)
			(size 0.254 0.7112)
			(layers "F.Cu" "F.Mask" "F.Paste")
			(net "VR_FET_SW_P12V_STBY_PVCCIN_CPU1")
		)
		(pad "31" smd rect
			(at 1.599946 -2.895092 90)
			(size 0.254 0.7112)
			(layers "F.Cu" "F.Mask" "F.Paste")
			(net "Net_359")
		)
		(pad "32" smd rect
			(at 1.150112 -2.895092 90)
			(size 0.254 0.7112)
			(layers "F.Cu" "F.Mask" "F.Paste")
			(net "VR_PVCCIN_CPU1_PH5_PHASE")
		)
		(pad "33" smd rect
			(at 0.700024 -2.895092 90)
			(size 0.254 0.7112)
			(layers "F.Cu" "F.Mask" "F.Paste")
			(net "VR_PVCCIN_CPU1_PH5_BOOT_R")
		)
		(pad "34" smd rect
			(at 0.249936 -2.895092 90)
			(size 0.254 0.7112)
			(layers "F.Cu" "F.Mask" "F.Paste")
			(net "VR_PVCCIN_CPU1_PWM5")
		)
		(pad "35" smd rect
			(at -0.199898 -2.895092 90)
			(size 0.254 0.7112)
			(layers "F.Cu" "F.Mask" "F.Paste")
			(net "P5V_STBY")
		)
		(pad "36" smd rect
			(at -0.649986 -2.895092 90)
			(size 0.254 0.7112)
			(layers "F.Cu" "F.Mask" "F.Paste")
			(net "A_TSENSE_PVCCIN_CPU1")
		)
		(pad "37" smd rect
			(at -1.100074 -2.895092 90)
			(size 0.254 0.7112)
			(layers "F.Cu" "F.Mask" "F.Paste")
			(net "VR_PVCCIN_CPU1_PH5_OCSET")
		)
		(pad "38" smd rect
			(at -1.549908 -2.895092 90)
			(size 0.254 0.7112)
			(layers "F.Cu" "F.Mask" "F.Paste")
			(net "ISENSE_PVCCIN_CPU1_PH5_IMON")
		)
		(pad "39" smd rect
			(at -1.999996 -2.895092 90)
			(size 0.254 0.7112)
			(layers "F.Cu" "F.Mask" "F.Paste")
			(net "VR_PVCCIN_CPU1_AIREF5")
		)
		(pad "40" smd rect
			(at -0.871728 -1.283208 90)
			(size 1.8034 2.0066)
			(layers "F.Cu" "F.Mask" "F.Paste")
			(net "GND")
		)
		(pad "41" smd rect
			(at -1.533906 0.247904 90)
			(size 0.508 0.3556)
			(layers "F.Cu" "F.Mask" "F.Paste")
			(net "TP_PVCCIN_CPU1_PH5_GL_1")
		)
	)
)
